FILE_TYPE = CONNECTIVITY;
{Allegro Design Entry HDL 17.2-2016 S081 (4005846) 1/11/2022}
"PAGE_NUMBER" = 222;
0"NC";
1"P3V3_AUX\g";
2"P3V3_AUX\g";
3"P3V3_AUX\g";
4"P3V3_AUX\g";
5"P3V3_AUX\g";
6"P3V3_AUX\g";
7"P3V3_AUX\g";
8"P3V3_AUX\g";
9"GND\g";
10"GND\g";
11"GND\g";
12"GND\g";
13"GND\g";
14"GND\g";
15"GND\g";
16"GND\g";
17"GND\g";
18"GND\g";
19"SMB_2_BMC_GPU_BUF_R_SCL"CDS_PHYS_NET_NAME"SMB_2_BMC_GPU_BUF_R_SCL";
20"SMB_2_BMC_GPU_BUF_R_SDA"CDS_PHYS_NET_NAME"SMB_2_BMC_GPU_BUF_R_SDA";
21"I3C_BMC_SWB_R_SCL"CDS_PHYS_NET_NAME"I3C_BMC_SWB_R_SCL";
22"I3C_BMC_SWB_R_SDA"CDS_PHYS_NET_NAME"I3C_BMC_SWB_R_SDA";
23"I3C_BMC_SWB_BUF_R_SDA"CDS_PHYS_NET_NAME"I3C_BMC_SWB_BUF_R_SDA";
24"I3C_BMC_SWB_BUF_R_SCL"CDS_PHYS_NET_NAME"I3C_BMC_SWB_BUF_R_SCL";
25"I3C_BMC_SWB_BUF_SCL"CDS_PHYS_NET_NAME"I3C_BMC_SWB_BUF_SCL";
26"SMB_2_BMC_GPU_BUF_SDA"CDS_PHYS_NET_NAME"SMB_2_BMC_GPU_BUF_SDA";
27"SMB_2_BMC_GPU_BUF_SCL"CDS_PHYS_NET_NAME"SMB_2_BMC_GPU_BUF_SCL";
28"SMB_1_BMC_GPU_BUF_SDA"CDS_PHYS_NET_NAME"SMB_1_BMC_GPU_BUF_SDA";
29"SMB_1_BMC_GPU_BUF_SCL"CDS_PHYS_NET_NAME"SMB_1_BMC_GPU_BUF_SCL";
30"I3C_BMC_SWB_BUF_SDA"CDS_PHYS_NET_NAME"I3C_BMC_SWB_BUF_SDA";
31"SMB_1_BMC_GPU_BUF_R_SCL"CDS_PHYS_NET_NAME"SMB_1_BMC_GPU_BUF_R_SCL";
32"SMB_1_BMC_GPU_BUF_R_SDA"CDS_PHYS_NET_NAME"SMB_1_BMC_GPU_BUF_R_SDA";
33"SMB_BMC_SWB_BUF_SDA"CDS_PHYS_NET_NAME"SMB_BMC_SWB_BUF_SDA";
34"SMB_BMC_SWB_BUF_SCL"CDS_PHYS_NET_NAME"SMB_BMC_SWB_BUF_SCL";
35"SMB_BMC_GPU_EN_R1"CDS_PHYS_NET_NAME"SMB_BMC_GPU_EN_R1";
36"SMB_BMC_SWB_BUF_R_SDA"CDS_PHYS_NET_NAME"SMB_BMC_SWB_BUF_R_SDA";
37"SMB_BMC_SWB_BUF_R_SCL"CDS_PHYS_NET_NAME"SMB_BMC_SWB_BUF_R_SCL";
38"SMB_1_BMC_GPU_R_SCL"CDS_PHYS_NET_NAME"SMB_1_BMC_GPU_R_SCL";
39"SMB_1_BMC_GPU_SCL"CDS_PHYS_NET_NAME"SMB_1_BMC_GPU_SCL";
40"SMB_1_BMC_GPU_SDA"CDS_PHYS_NET_NAME"SMB_1_BMC_GPU_SDA";
41"SMB_BMC_SWB_R_SCL";
42"SMB_BMC_SWB_R_SDA";
43"SMB_BMC_GPU_EN";
44"SMB_BMC_SWB_EN_R"CDS_PHYS_NET_NAME"SMB_BMC_SWB_EN_R";
45"SMB_BMC_SWB_SDA"CDS_PHYS_NET_NAME"SMB_BMC_SWB_SDA";
46"SMB_BMC_SWB_EN";
47"SMB_BMC_SWB_SCL"CDS_PHYS_NET_NAME"SMB_BMC_SWB_SCL";
48"SMB_1_BMC_GPU_R_SDA"CDS_PHYS_NET_NAME"SMB_1_BMC_GPU_R_SDA";
49"SMB_BMC_SWB_EN_R2"CDS_PHYS_NET_NAME"SMB_BMC_SWB_EN_R2";
50"SMB_BMC_SWB_EN";
51"I3C_BMC_SWB_SCL";
52"I3C_BMC_SWB_SDA";
53"SMB_2_BMC_GPU_R_SDA";
54"SMB_2_BMC_GPU_R_SCL";
55"SMB_BMC_GPU_EN_R3"CDS_PHYS_NET_NAME"SMB_BMC_GPU_EN_R3";
56"SMB_2_BMC_GPU_SDA"CDS_PHYS_NET_NAME"SMB_2_BMC_GPU_SDA";
57"SMB_2_BMC_GPU_SCL"CDS_PHYS_NET_NAME"SMB_2_BMC_GPU_SCL";
58"SMB_BMC_GPU_EN";
%"UNIVERSAL_GND"
"1","(-5250,5750)","0","logical_power","I10";
;
CDS_LIB"logical_power"
HDL_POWER"GND";
"A"9;
%"LTC4307CMS8"
"1","(-4850,6025)","0","pure_quanta","I11";
;
PART_NUMBER"AL004307000"
VALUE"LTC4307CMS8"
PART_TYPE"SMLF"
MATERIAL"IC"
LOCATION"U200"
CDS_LIB"pure_quanta"
NEEDS_NO_SIZE"TRUE"
$SEC"1"
CDS_SEC"1";
"READY"
$PN"5"0;
"SDA_OUT"
$PN"7"20;
"SCL_OUT"
$PN"2"19;
"VCC"
$PN"8"1;
"GND"
$PN"4"9;
"SDA_IN"
$PN"6"53;
"SCL_IN"
$PN"3"54;
"ENABLE"
$PN"1"55;
%"Q_RES"
"1","(-4875,5550)","0","pure_quanta","I12";
;
PART_NUMBER"CS00002JB13"
MATERIAL"EMPTY"
WATTAGE"1/16W"
PACK_TYPE"0402LF"
VALUE"0"
TOLERANCE"5%"
$LOCATION"R2987"
CDS_LIB"pure_quanta"
CDS_LOCATION"R2987"
$SEC"1"
CDS_SEC"1";
"B"
$PN"2"20;
"A"
$PN"1"53;
%"Q_RES"
"1","(-4875,5625)","0","pure_quanta","I13";
;
PART_NUMBER"CS00002JB13"
MATERIAL"EMPTY"
VALUE"0"
$LOCATION"R2986"
WATTAGE"1/16W"
TOLERANCE"5%"
PACK_TYPE"0402LF"
CDS_LIB"pure_quanta"
CDS_LOCATION"R2986"
$SEC"1"
CDS_SEC"1";
"B"
$PN"2"19;
"A"
$PN"1"54;
%"UNIVERSAL_GND"
"1","(-5050,6900)","0","logical_power","I14";
;
CDS_LIB"logical_power"
HDL_POWER"GND";
"A"10;
%"UNIVERSAL_GND"
"1","(-4825,4100)","0","logical_power","I15";
;
CDS_LIB"logical_power"
HDL_POWER"GND";
"A"11;
%"Q_RES"
"2","(-4825,4300)","0","pure_quanta","I16";
;
PART_NUMBER"CS31002FB08"
TOLERANCE"1%"
PACK_TYPE"0402LF"
MATERIAL"CHIP"
VALUE"10K"
WATTAGE"1/16W"
$LOCATION"R2666"
CDS_LIB"pure_quanta"
CDS_LOCATION"R2666"
$SEC"1"
CDS_SEC"1";
"A"
$PN"1"50;
"B"
$PN"2"11;
%"Q_RES"
"1","(-4050,4550)","0","pure_quanta","I17";
;
PART_NUMBER"CS00002JB13"
TOLERANCE"5%"
VALUE"0"
MATERIAL"CHIP"
LOCATION"R3111"
PACK_TYPE"0402LF"
WATTAGE"1/16W"
CDS_LIB"pure_quanta"
$SEC"1"
CDS_SEC"1";
"B"
$PN"2"22;
"A"
$PN"1"52;
%"Q_RES"
"1","(-4050,4650)","0","pure_quanta","I18";
;
PART_NUMBER"CS03322FB03"
VALUE"33.2"
MATERIAL"CHIP"
TOLERANCE"1%"
LOCATION"R3112"
CDS_LIB"pure_quanta"
PACK_TYPE"0402LF"
WATTAGE"1/16W"
$SEC"1"
CDS_SEC"1";
"B"
$PN"2"21;
"A"
$PN"1"51;
%"Q_RES"
"1","(-4050,4750)","0","pure_quanta","I19";
;
PART_NUMBER"CS00002JB13"
MATERIAL"CHIP"
WATTAGE"1/16W"
PACK_TYPE"0402LF"
VALUE"0"
TOLERANCE"5%"
$LOCATION"R2676"
CDS_LIB"pure_quanta"
CDS_LOCATION"R2676"
$SEC"1"
CDS_SEC"1";
"B"
$PN"2"49;
"A"
$PN"1"50;
%"Q_CAP"
"1","(-4125,6425)","0","pure_quanta","I20";
;
PART_NUMBER"CH4104K1B00"
VALUE"0.1UF"
VOLTAGE"25V"
MATERIAL"X7R"
PACK_TYPE"0402"
TOLERANCE"10%"
$LOCATION"C1796"
CDS_LIB"pure_quanta"
CDS_LOCATION"C1796"
$SEC"1"
CDS_SEC"1";
"B"
$PN"2"12;
"A"
$PN"1"1;
%"UNIVERSAL_GND"
"1","(-4125,6200)","0","logical_power","I21";
;
CDS_LIB"logical_power"
HDL_POWER"GND";
"A"12;
%"UNIVERSAL_POWER"
"1","(-4300,6725)","0","logical_power","I22";
;
HDL_POWER"P3V3_AUX"
CDS_LIB"logical_power";
"A"1;
%"Q_RES"
"2","(-3375,6400)","0","pure_quanta","I23";
;
PART_NUMBER"CS35492FB03"
PACK_TYPE"0402LF"
VALUE"54.9K"
TOLERANCE"1%"
WATTAGE"1/16W"
MATERIAL"CHIP"
$LOCATION"R3521"
CDS_LIB"pure_quanta"
CDS_LOCATION"R3521"
$SEC"1"
CDS_SEC"1";
"A"
$PN"1"2;
"B"
$PN"2"19;
%"UNIVERSAL_POWER"
"1","(-3375,6725)","0","logical_power","I24";
;
HDL_POWER"P3V3_AUX"
CDS_LIB"logical_power";
"A"2;
%"Q_RES"
"2","(-3125,6400)","0","pure_quanta","I25";
;
PART_NUMBER"CS35492FB03"
PACK_TYPE"0402LF"
VALUE"54.9K"
TOLERANCE"1%"
WATTAGE"1/16W"
MATERIAL"CHIP"
$LOCATION"R3522"
CDS_LIB"pure_quanta"
CDS_LOCATION"R3522"
$SEC"1"
CDS_SEC"1";
"A"
$PN"1"2;
"B"
$PN"2"20;
%"Q_RES"
"1","(-2825,6075)","0","pure_quanta","I26";
;
PART_NUMBER"CS03322FB03"
WATTAGE"1/16W"
PACK_TYPE"0402LF"
TOLERANCE"1%"
VALUE"33.2"
MATERIAL"CHIP"
$LOCATION"R2990"
CDS_LIB"pure_quanta"
CDS_LOCATION"R2990"
$SEC"1"
CDS_SEC"1";
"B"
$PN"2"27;
"A"
$PN"1"19;
%"Q_RES"
"1","(-2825,5975)","0","pure_quanta","I27";
;
PART_NUMBER"CS03322FB03"
VALUE"33.2"
TOLERANCE"1%"
MATERIAL"CHIP"
$LOCATION"R2991"
CDS_LIB"pure_quanta"
PACK_TYPE"0402LF"
WATTAGE"1/16W"
CDS_LOCATION"R2991"
$SEC"1"
CDS_SEC"1";
"B"
$PN"2"26;
"A"
$PN"1"20;
%"UNIVERSAL_GND"
"1","(-2825,4325)","0","logical_power","I28";
;
CDS_LIB"logical_power"
HDL_POWER"GND";
"A"13;
%"Q_RES"
"1","(-2325,3825)","0","pure_quanta","I29";
;
PART_NUMBER"CS00002JB13"
MATERIAL"CHIP"
PACK_TYPE"0402LF"
VALUE"0"
WATTAGE"1/16W"
TOLERANCE"5%"
$LOCATION"R2725"
CDS_LIB"pure_quanta"
CDS_LOCATION"R2725"
$SEC"1"
CDS_SEC"1";
"B"
$PN"2"24;
"A"
$PN"1"21;
%"Q_RES"
"1","(-2325,3900)","0","pure_quanta","I30";
;
PART_NUMBER"CS00002JB13"
VALUE"0"
MATERIAL"CHIP"
$LOCATION"R2706"
WATTAGE"1/16W"
TOLERANCE"5%"
PACK_TYPE"0402LF"
CDS_LIB"pure_quanta"
CDS_LOCATION"R2706"
$SEC"1"
CDS_SEC"1";
"B"
$PN"2"23;
"A"
$PN"1"22;
%"LTC4307CMS8"
"1","(-2275,4600)","0","pure_quanta","I31";
;
PART_NUMBER"AL004307000"
VALUE"LTC4307CMS8"
PART_TYPE"SMLF"
MATERIAL"EMPTY"
LOCATION"U176"
NEEDS_NO_SIZE"TRUE"
CDS_LIB"pure_quanta"
$SEC"1"
CDS_SEC"1";
"READY"
$PN"5"0;
"SDA_OUT"
$PN"7"23;
"SCL_OUT"
$PN"2"24;
"VCC"
$PN"8"3;
"GND"
$PN"4"13;
"SDA_IN"
$PN"6"22;
"SCL_IN"
$PN"3"21;
"ENABLE"
$PN"1"49;
%"UNIVERSAL_GND"
"1","(-1625,4825)","0","logical_power","I32";
;
CDS_LIB"logical_power"
HDL_POWER"GND";
"A"14;
%"Q_RES"
"1","(-2275,6900)","0","pure_quanta","I33";
;
PART_NUMBER"CS00002JB13"
VALUE"0"
PACK_TYPE"0402LF"
MATERIAL"EMPTY"
TOLERANCE"5%"
WATTAGE"1/16W"
$LOCATION"R2894"
CDS_LIB"pure_quanta"
CDS_LOCATION"R2894"
$SEC"1"
CDS_SEC"1";
"B"
$PN"2"32;
"A"
$PN"1"48;
%"Q_CAP"
"1","(-1625,5050)","0","pure_quanta","I34";
;
PART_NUMBER"CH4104K1B00"
PACK_TYPE"0402"
VALUE"0.1UF"
VOLTAGE"25V"
TOLERANCE"10%"
MATERIAL"EMPTY"
$LOCATION"C1708"
CDS_LIB"pure_quanta"
CDS_LOCATION"C1708"
$SEC"1"
CDS_SEC"1";
"B"
$PN"2"14;
"A"
$PN"1"3;
%"UNIVERSAL_POWER"
"1","(-1800,5350)","0","logical_power","I35";
;
HDL_POWER"P3V3_AUX"
CDS_LIB"logical_power";
"A"3;
%"Q_RES"
"1","(-2275,6975)","0","pure_quanta","I38";
;
PART_NUMBER"CS00002JB13"
MATERIAL"EMPTY"
VALUE"0"
$LOCATION"R2893"
CDS_LIB"pure_quanta"
PACK_TYPE"0402LF"
TOLERANCE"5%"
WATTAGE"1/16W"
CDS_LOCATION"R2893"
$SEC"1"
CDS_SEC"1";
"B"
$PN"2"31;
"A"
$PN"1"38;
%"Q_RES"
"1","(-6125,8700)","0","pure_quanta","I42";
;
PART_NUMBER"CS00002JB13"
PACK_TYPE"0402LF"
MATERIAL"CHIP"
TOLERANCE"5%"
VALUE"0"
WATTAGE"1/16W"
$LOCATION"R3106"
CDS_LIB"pure_quanta"
CDS_LOCATION"R3106"
$SEC"1"
CDS_SEC"1";
"B"
$PN"2"42;
"A"
$PN"1"45;
%"Q_RES"
"1","(-6125,8800)","0","pure_quanta","I43";
;
PART_NUMBER"CS00002JB13"
MATERIAL"CHIP"
TOLERANCE"5%"
VALUE"0"
$LOCATION"R3105"
PACK_TYPE"0402LF"
WATTAGE"1/16W"
CDS_LIB"pure_quanta"
CDS_LOCATION"R3105"
$SEC"1"
CDS_SEC"1";
"B"
$PN"2"41;
"A"
$PN"1"47;
%"Q_RES"
"1","(-6125,8900)","0","pure_quanta","I44";
;
PART_NUMBER"CS00002JB13"
TOLERANCE"5%"
VALUE"0"
MATERIAL"CHIP"
$LOCATION"R2707"
WATTAGE"1/16W"
PACK_TYPE"0402LF"
CDS_LIB"pure_quanta"
CDS_LOCATION"R2707"
$SEC"1"
CDS_SEC"1";
"B"
$PN"2"44;
"A"
$PN"1"46;
%"Q_RES"
"2","(-5050,7100)","0","pure_quanta","I48";
;
PART_NUMBER"CS31002FB08"
WATTAGE"1/16W"
PACK_TYPE"0402LF"
VALUE"10K"
TOLERANCE"1%"
MATERIAL"CHIP"
$LOCATION"R4603"
CDS_LIB"pure_quanta"
CDS_LOCATION"R4603"
$SEC"1"
CDS_SEC"1";
"A"
$PN"1"43;
"B"
$PN"2"10;
%"UNIVERSAL_GND"
"1","(-5025,8475)","0","logical_power","I49";
;
CDS_LIB"logical_power"
HDL_POWER"GND";
"A"15;
%"LTC4307CMS8"
"1","(-4625,8750)","0","pure_quanta","I50";
;
PART_NUMBER"AL004307000"
MATERIAL"IC"
VALUE"LTC4307CMS8"
PART_TYPE"SMLF"
LOCATION"U175"
NEEDS_NO_SIZE"TRUE"
CDS_LIB"pure_quanta"
$SEC"1"
CDS_SEC"1";
"READY"
$PN"5"0;
"SDA_OUT"
$PN"7"36;
"SCL_OUT"
$PN"2"37;
"VCC"
$PN"8"4;
"GND"
$PN"4"15;
"SDA_IN"
$PN"6"42;
"SCL_IN"
$PN"3"41;
"ENABLE"
$PN"1"44;
%"Q_RES"
"1","(-4100,7425)","0","pure_quanta","I51";
;
PART_NUMBER"CS00002JB13"
MATERIAL"CHIP"
VALUE"0"
TOLERANCE"5%"
$LOCATION"R3109"
WATTAGE"1/16W"
PACK_TYPE"0402LF"
CDS_LIB"pure_quanta"
CDS_LOCATION"R3109"
$SEC"1"
CDS_SEC"1";
"B"
$PN"2"38;
"A"
$PN"1"39;
%"Q_RES"
"1","(-4100,7325)","0","pure_quanta","I52";
;
PART_NUMBER"CS00002JB13"
VALUE"0"
PACK_TYPE"0402LF"
TOLERANCE"5%"
MATERIAL"CHIP"
WATTAGE"1/16W"
$LOCATION"R3110"
CDS_LIB"pure_quanta"
CDS_LOCATION"R3110"
$SEC"1"
CDS_SEC"1";
"B"
$PN"2"48;
"A"
$PN"1"40;
%"Q_RES"
"1","(-4100,7525)","0","pure_quanta","I53";
;
PART_NUMBER"CS00002JB13"
TOLERANCE"5%"
MATERIAL"CHIP"
VALUE"0"
$LOCATION"R2899"
CDS_LIB"pure_quanta"
PACK_TYPE"0402LF"
WATTAGE"1/16W"
CDS_LOCATION"R2899"
$SEC"1"
CDS_SEC"1";
"B"
$PN"2"35;
"A"
$PN"1"43;
%"Q_RES"
"1","(-4650,8275)","0","pure_quanta","I54";
;
PART_NUMBER"CS00002JB13"
MATERIAL"EMPTY"
VALUE"0"
WATTAGE"1/16W"
PACK_TYPE"0402LF"
TOLERANCE"5%"
$LOCATION"R2724"
CDS_LIB"pure_quanta"
CDS_LOCATION"R2724"
$SEC"1"
CDS_SEC"1";
"B"
$PN"2"36;
"A"
$PN"1"42;
%"Q_RES"
"1","(-4650,8350)","0","pure_quanta","I55";
;
PART_NUMBER"CS00002JB13"
VALUE"0"
MATERIAL"EMPTY"
$LOCATION"R2705"
WATTAGE"1/16W"
TOLERANCE"5%"
PACK_TYPE"0402LF"
CDS_LIB"pure_quanta"
CDS_LOCATION"R2705"
$SEC"1"
CDS_SEC"1";
"B"
$PN"2"37;
"A"
$PN"1"41;
%"UNIVERSAL_GND"
"1","(-4000,8925)","0","logical_power","I56";
;
CDS_LIB"logical_power"
HDL_POWER"GND";
"A"16;
%"UNIVERSAL_POWER"
"1","(-4175,9450)","0","logical_power","I57";
;
HDL_POWER"P3V3_AUX"
CDS_LIB"logical_power";
"A"4;
%"Q_CAP"
"1","(-4000,9150)","0","pure_quanta","I58";
;
PART_NUMBER"CH4104K1B00"
VALUE"0.1UF"
VOLTAGE"25V"
TOLERANCE"10%"
MATERIAL"X7R"
PACK_TYPE"0402"
$LOCATION"C1707"
CDS_LIB"pure_quanta"
CDS_LOCATION"C1707"
$SEC"1"
CDS_SEC"1";
"B"
$PN"2"16;
"A"
$PN"1"4;
%"Q_RES"
"2","(-3150,9125)","0","pure_quanta","I59";
;
PART_NUMBER"CS31002FB08"
WATTAGE"1/16W"
MATERIAL"CHIP"
PACK_TYPE"0402LF"
TOLERANCE"1%"
VALUE"10K"
$LOCATION"R2667"
CDS_LIB"pure_quanta"
CDS_LOCATION"R2667"
$SEC"1"
CDS_SEC"1";
"A"
$PN"1"5;
"B"
$PN"2"37;
%"UNIVERSAL_POWER"
"1","(-3150,9450)","0","logical_power","I60";
;
HDL_POWER"P3V3_AUX"
CDS_LIB"logical_power";
"A"5;
%"Q_RES"
"2","(-2900,9125)","0","pure_quanta","I61";
;
PART_NUMBER"CS31002FB08"
MATERIAL"CHIP"
WATTAGE"1/16W"
PACK_TYPE"0402LF"
TOLERANCE"1%"
VALUE"10K"
$LOCATION"R2669"
CDS_LIB"pure_quanta"
CDS_LOCATION"R2669"
$SEC"1"
CDS_SEC"1";
"A"
$PN"1"5;
"B"
$PN"2"36;
%"UNIVERSAL_GND"
"1","(-2725,7100)","0","logical_power","I62";
;
CDS_LIB"logical_power"
HDL_POWER"GND";
"A"17;
%"LTC4307CMS8"
"1","(-2250,7375)","0","pure_quanta","I63";
;
PART_NUMBER"AL004307000"
VALUE"LTC4307CMS8"
MATERIAL"IC"
PART_TYPE"SMLF"
LOCATION"U194"
CDS_LIB"pure_quanta"
NEEDS_NO_SIZE"TRUE"
$SEC"1"
CDS_SEC"1";
"READY"
$PN"5"0;
"SDA_OUT"
$PN"7"32;
"SCL_OUT"
$PN"2"31;
"VCC"
$PN"8"6;
"GND"
$PN"4"17;
"SDA_IN"
$PN"6"48;
"SCL_IN"
$PN"3"38;
"ENABLE"
$PN"1"35;
%"Q_RES"
"1","(-2600,8700)","0","pure_quanta","I64";
;
PART_NUMBER"CS03322FB03"
TOLERANCE"1%"
VALUE"33.2"
MATERIAL"CHIP"
$LOCATION"R2672"
CDS_LIB"pure_quanta"
PACK_TYPE"0402LF"
WATTAGE"1/16W"
CDS_LOCATION"R2672"
$SEC"1"
CDS_SEC"1";
"B"
$PN"2"33;
"A"
$PN"1"36;
%"Q_RES"
"1","(-2600,8800)","0","pure_quanta","I65";
;
PART_NUMBER"CS03322FB03"
TOLERANCE"1%"
MATERIAL"CHIP"
PACK_TYPE"0402LF"
VALUE"33.2"
WATTAGE"1/16W"
$LOCATION"R2671"
CDS_LIB"pure_quanta"
CDS_LOCATION"R2671"
$SEC"1"
CDS_SEC"1";
"B"
$PN"2"34;
"A"
$PN"1"37;
%"Q_CAP"
"1","(-1525,7775)","0","pure_quanta","I66";
;
PART_NUMBER"CH4104K1B00"
VALUE"0.1UF"
MATERIAL"X7R"
VOLTAGE"25V"
TOLERANCE"10%"
PACK_TYPE"0402"
$LOCATION"C1766"
CDS_LIB"pure_quanta"
CDS_LOCATION"C1766"
$SEC"1"
CDS_SEC"1";
"B"
$PN"2"18;
"A"
$PN"1"6;
%"UNIVERSAL_GND"
"1","(-1525,7550)","0","logical_power","I67";
;
CDS_LIB"logical_power"
HDL_POWER"GND";
"A"18;
%"UNIVERSAL_POWER"
"1","(-1700,8075)","0","logical_power","I68";
;
HDL_POWER"P3V3_AUX"
CDS_LIB"logical_power";
"A"6;
%"Q_RES"
"1","(-6175,5975)","0","pure_quanta","I7";
;
PART_NUMBER"CS00002JB13"
PACK_TYPE"0402LF"
MATERIAL"CHIP"
TOLERANCE"5%"
VALUE"0"
WATTAGE"1/16W"
$LOCATION"R3108"
CDS_LIB"pure_quanta"
CDS_LOCATION"R3108"
$SEC"1"
CDS_SEC"1";
"B"
$PN"2"53;
"A"
$PN"1"56;
%"Q_RES"
"1","(-150,4550)","0","pure_quanta","I71";
;
PART_NUMBER"CS02742FB03"
WATTAGE"1/16W"
PACK_TYPE"0402LF"
MATERIAL"CHIP"
TOLERANCE"1%"
VALUE"27.4"
$LOCATION"R2674"
CDS_LIB"pure_quanta"
CDS_LOCATION"R2674"
$SEC"1"
CDS_SEC"1";
"B"
$PN"2"30;
"A"
$PN"1"23;
%"Q_RES"
"1","(-150,4650)","0","pure_quanta","I72";
;
PART_NUMBER"CS03322FB03"
MATERIAL"CHIP"
TOLERANCE"1%"
VALUE"33.2"
$LOCATION"R2675"
CDS_LIB"pure_quanta"
PACK_TYPE"0402LF"
WATTAGE"1/16W"
CDS_LOCATION"R2675"
$SEC"1"
CDS_SEC"1";
"B"
$PN"2"25;
"A"
$PN"1"24;
%"Q_RES"
"2","(-700,5025)","0","pure_quanta","I75";
;
PART_NUMBER"CS24702JB10"
WATTAGE"1/16W"
MATERIAL"EMPTY"
PACK_TYPE"0402LF"
TOLERANCE"5%"
VALUE"4.7K"
$LOCATION"R2668"
CDS_LIB"pure_quanta"
CDS_LOCATION"R2668"
$SEC"1"
CDS_SEC"1";
"A"
$PN"1"7;
"B"
$PN"2"23;
%"UNIVERSAL_POWER"
"1","(-700,5350)","0","logical_power","I76";
;
HDL_POWER"P3V3_AUX"
CDS_LIB"logical_power";
"A"7;
%"Q_RES"
"2","(-450,5025)","0","pure_quanta","I77";
;
PART_NUMBER"CS24702JB10"
TOLERANCE"5%"
VALUE"4.7K"
WATTAGE"1/16W"
MATERIAL"EMPTY"
PACK_TYPE"0402LF"
$LOCATION"R2670"
CDS_LIB"pure_quanta"
CDS_LOCATION"R2670"
$SEC"1"
CDS_SEC"1";
"A"
$PN"1"7;
"B"
$PN"2"24;
%"Q_RES"
"1","(-225,7425)","0","pure_quanta","I78";
;
PART_NUMBER"CS03322FB03"
MATERIAL"CHIP"
VALUE"33.2"
TOLERANCE"1%"
PACK_TYPE"0402LF"
WATTAGE"1/16W"
$LOCATION"R2897"
CDS_LIB"pure_quanta"
CDS_LOCATION"R2897"
$SEC"1"
CDS_SEC"1";
"B"
$PN"2"29;
"A"
$PN"1"31;
%"Q_RES"
"1","(-225,7325)","0","pure_quanta","I79";
;
PART_NUMBER"CS03322FB03"
TOLERANCE"1%"
MATERIAL"CHIP"
VALUE"33.2"
$LOCATION"R2898"
WATTAGE"1/16W"
PACK_TYPE"0402LF"
CDS_LIB"pure_quanta"
CDS_LOCATION"R2898"
$SEC"1"
CDS_SEC"1";
"B"
$PN"2"28;
"A"
$PN"1"32;
%"Q_RES"
"1","(-6175,6075)","0","pure_quanta","I8";
;
PART_NUMBER"CS00002JB13"
MATERIAL"CHIP"
TOLERANCE"5%"
VALUE"0"
$LOCATION"R3107"
CDS_LIB"pure_quanta"
WATTAGE"1/16W"
PACK_TYPE"0402LF"
CDS_LOCATION"R3107"
$SEC"1"
CDS_SEC"1";
"B"
$PN"2"54;
"A"
$PN"1"57;
%"Q_RES"
"2","(-775,7750)","0","pure_quanta","I80";
;
PART_NUMBER"CS35492FB03"
PACK_TYPE"0402LF"
VALUE"54.9K"
TOLERANCE"1%"
WATTAGE"1/16W"
MATERIAL"CHIP"
$LOCATION"R3523"
CDS_LIB"pure_quanta"
CDS_LOCATION"R3523"
$SEC"1"
CDS_SEC"1";
"A"
$PN"1"8;
"B"
$PN"2"31;
%"Q_RES"
"2","(-525,7750)","0","pure_quanta","I81";
;
PART_NUMBER"CS35492FB03"
MATERIAL"CHIP"
WATTAGE"1/16W"
TOLERANCE"1%"
VALUE"54.9K"
PACK_TYPE"0402LF"
$LOCATION"R3524"
CDS_LIB"pure_quanta"
CDS_LOCATION"R3524"
$SEC"1"
CDS_SEC"1";
"A"
$PN"1"8;
"B"
$PN"2"32;
%"UNIVERSAL_POWER"
"1","(-775,8075)","0","logical_power","I82";
;
HDL_POWER"P3V3_AUX"
CDS_LIB"logical_power";
"A"8;
%"Q_RES"
"1","(-6175,6175)","0","pure_quanta","I9";
;
PART_NUMBER"CS00002JB13"
MATERIAL"CHIP"
VALUE"0"
TOLERANCE"5%"
$LOCATION"R2992"
CDS_LIB"pure_quanta"
PACK_TYPE"0402LF"
WATTAGE"1/16W"
CDS_LOCATION"R2992"
$SEC"1"
CDS_SEC"1";
"B"
$PN"2"55;
"A"
$PN"1"58;
END.
